(kicad_pcb
	(version 20260206)
	(generator "pcbnew")
	(generator_version "10.0")
	(general
		(thickness 1.6)
		(legacy_teardrops no)
	)
	(paper "A4")
	(title_block
		(title "Bryce Canyon_R.DPB_16317-1_OCP.brd")
		(comment 1 "Bryce Canyon / footprints 786-788 of 2099")
	)
	(layers
		(0 "F.Cu" signal "TOP")
		(4 "In1.Cu" signal "L2GND")
		(6 "In2.Cu" signal "L3")
		(8 "In3.Cu" signal "L4VCC")
		(10 "In4.Cu" signal "L5VCC")
		(12 "In5.Cu" signal "L6")
		(14 "In6.Cu" signal "L7GND")
		(2 "B.Cu" signal "BOTTOM")
		(9 "F.Adhes" user "F.Adhesive")
		(11 "B.Adhes" user "B.Adhesive")
		(13 "F.Paste" user "Package Geometry/Pastemask Top")
		(15 "B.Paste" user "Package Geometry/Pastemask Bottom")
		(5 "F.SilkS" user "Ref Des/Silkscreen Top")
		(7 "B.SilkS" user "Ref Des/Silkscreen Bottom")
		(1 "F.Mask" user "Board Geometry/Soldermask Top")
		(3 "B.Mask" user "Board Geometry/Soldermask Bottom")
		(17 "Dwgs.User" user "User.Drawings")
		(19 "Cmts.User" user "User.Comments")
		(21 "Eco1.User" user "User.Eco1")
		(23 "Eco2.User" user "User.Eco2")
		(25 "Edge.Cuts" user "Board Geometry/Outline")
		(27 "Margin" user)
		(31 "F.CrtYd" user "Package Geometry/Place Bound Top")
		(29 "B.CrtYd" user "Package Geometry/Place Bound Bottom")
		(35 "F.Fab" user "Ref Des/Assembly Top")
		(33 "B.Fab" user "Ref Des/Assembly Bottom")
	)
	(footprint ""
		(layer "F.Cu")
		(at 388.649972 -143.91005 -90)
		(property "Reference" "HDDSAS20"
			(at 0 0 270)
			(layer "F.SilkS")
			(hide yes)
			(effects
				(font
					(size 1.27 1.27)
				)
			)
		)
		(property "Value" "SKT-SAS15P-14P-45-GP"
			(at -20.7645 -8.9789 270)
			(unlocked yes)
			(layer "F.Fab")
			(hide yes)
			(effects
				(font
					(size 1.016 1.016)
					(thickness 0.1524)
				)
			)
		)
		(property "Device Type" "10120818-001C-TRLF"
			(at -20.7645 -10.5029 270)
			(unlocked yes)
			(layer "F.Fab")
			(hide yes)
			(effects
				(font
					(size 1.016 1.016)
					(thickness 0.1524)
				)
			)
		)
		(duplicate_pad_numbers_are_jumpers no)
		(fp_line
			(start 1.651 4.2926)
			(end 1.651 3.0099)
			(stroke
				(width 0.1524)
				(type default)
			)
			(layer "F.SilkS")
		)
		(fp_line
			(start 8.509 4.2926)
			(end 1.651 4.2926)
			(stroke
				(width 0.1524)
				(type default)
			)
			(layer "F.SilkS")
		)
		(fp_line
			(start -23.4188 3.0099)
			(end -23.4188 -3.2512)
			(stroke
				(width 0.1524)
				(type default)
			)
			(layer "F.SilkS")
		)
		(fp_line
			(start 1.651 3.0099)
			(end -23.4188 3.0099)
			(stroke
				(width 0.1524)
				(type default)
			)
			(layer "F.SilkS")
		)
		(fp_line
			(start 8.509 3.0099)
			(end 8.509 4.2926)
			(stroke
				(width 0.1524)
				(type default)
			)
			(layer "F.SilkS")
		)
		(fp_line
			(start 23.4188 3.0099)
			(end 8.509 3.0099)
			(stroke
				(width 0.1524)
				(type default)
			)
			(layer "F.SilkS")
		)
		(fp_line
			(start -23.4188 -3.2512)
			(end 23.4188 -3.2512)
			(stroke
				(width 0.1524)
				(type default)
			)
			(layer "F.SilkS")
		)
		(fp_line
			(start 23.4188 -3.2512)
			(end 23.4188 3.0099)
			(stroke
				(width 0.1524)
				(type default)
			)
			(layer "F.SilkS")
		)
		(fp_line
			(start 15.5067 -3.3401)
			(end 16.2687 -3.3401)
			(stroke
				(width 0.3302)
				(type default)
			)
			(layer "F.SilkS")
		)
		(fp_poly
			(pts
				(xy 15.868904 -3.230372) (xy 16.503904 -3.865372) (xy 15.233904 -3.865372)
			)
			(stroke
				(width 0)
				(type default)
			)
			(fill yes)
			(layer "F.SilkS")
		)
		(fp_poly
			(pts
				(xy -22.8727 -2.7559) (xy 22.8727 -2.7559) (xy 22.8727 2.7559) (xy 8.255 2.7559) (xy 8.255 3.5179)
				(xy 1.905 3.5179) (xy 1.905 2.7559) (xy -22.8727 2.7559)
			)
			(stroke
				(width 0)
				(type default)
			)
			(fill no)
			(layer "F.CrtYd")
		)
		(fp_poly
			(pts
				(xy 1.397 4.5466) (xy 1.397 3.2639) (xy -23.6728 3.2639) (xy -23.6728 -3.5052) (xy 23.6728 -3.5052)
				(xy 23.6728 -0.00635) (xy 22.8727 -0.00635) (xy 22.8727 -2.7559) (xy -22.8727 -2.7559) (xy -22.8727 2.7559)
				(xy 1.905 2.7559) (xy 1.905 3.5179) (xy 8.255 3.5179) (xy 8.255 2.7559) (xy 22.8727 2.7559) (xy 22.8727 0.00635)
				(xy 23.6728 0.00635) (xy 23.6728 3.2639) (xy 8.763 3.2639) (xy 8.763 4.5466)
			)
			(stroke
				(width 0)
				(type default)
			)
			(fill no)
			(layer "F.CrtYd")
		)
		(fp_poly
			(pts
				(xy 1.397 4.5466) (xy 1.397 3.2639) (xy -23.6728 3.2639) (xy -23.6728 -3.5052) (xy 23.6728 -3.5052)
				(xy 23.6728 3.2639) (xy 8.763 3.2639) (xy 8.763 4.5466)
			)
			(stroke
				(width 0)
				(type default)
			)
			(fill no)
			(layer "F.Fab")
		)
		(pad "" np_thru_hole circle
			(at -18.874994 0 270)
			(size 0.254 0.254)
			(drill 1.3462)
			(layers "*.Cu" "*.Mask")
			(clearance 0.9017)
			(thermal_gap 0.9017)
		)
		(pad "" np_thru_hole circle
			(at 18.874994 0 270)
			(size 0.254 0.254)
			(drill 0.9398)
			(layers "*.Cu" "*.Mask")
			(clearance 0.6985)
			(thermal_gap 0.6985)
		)
		(pad "G1" smd rect
			(at 21.874988 0 270)
			(size 2.5908 2.5908)
			(layers "F.Cu" "F.Mask" "F.Paste")
			(net "GND")
		)
		(pad "G2" smd rect
			(at -21.874988 0 270)
			(size 2.5908 2.5908)
			(layers "F.Cu" "F.Mask" "F.Paste")
			(net "GND")
		)
		(pad "P1" smd rect
			(at 1.905 -1.82499 270)
			(size 0.6096 2.3622)
			(layers "F.Cu" "F.Mask" "F.Paste")
			(net "Net_1699")
		)
		(pad "P2" smd rect
			(at 0.635 -1.82499 270)
			(size 0.6096 2.3622)
			(layers "F.Cu" "F.Mask" "F.Paste")
			(net "Net_1700")
		)
		(pad "P3" smd rect
			(at -0.635 -1.82499 270)
			(size 0.6096 2.3622)
			(layers "F.Cu" "F.Mask" "F.Paste")
			(net "Net_1701")
		)
		(pad "P4" smd rect
			(at -1.905 -1.82499 270)
			(size 0.6096 2.3622)
			(layers "F.Cu" "F.Mask" "F.Paste")
			(net "GND")
		)
		(pad "P5" smd rect
			(at -3.175 -1.82499 270)
			(size 0.6096 2.3622)
			(layers "F.Cu" "F.Mask" "F.Paste")
			(net "HDD_PRSNT_20")
		)
		(pad "P6" smd rect
			(at -4.445 -1.82499 270)
			(size 0.6096 2.3622)
			(layers "F.Cu" "F.Mask" "F.Paste")
			(net "GND")
		)
		(pad "P7" smd rect
			(at -5.715 -1.82499 270)
			(size 0.6096 2.3622)
			(layers "F.Cu" "F.Mask" "F.Paste")
			(net "5V_PRE_20")
		)
		(pad "P8" smd rect
			(at -6.985 -1.82499 270)
			(size 0.6096 2.3622)
			(layers "F.Cu" "F.Mask" "F.Paste")
			(net "P5V_HDD20")
		)
		(pad "P9" smd rect
			(at -8.255 -1.82499 270)
			(size 0.6096 2.3622)
			(layers "F.Cu" "F.Mask" "F.Paste")
			(net "P5V_HDD20")
		)
		(pad "P10" smd rect
			(at -9.525 -1.82499 270)
			(size 0.6096 2.3622)
			(layers "F.Cu" "F.Mask" "F.Paste")
			(net "GND")
		)
		(pad "P11" smd rect
			(at -10.795 -1.82499 270)
			(size 0.6096 2.3622)
			(layers "F.Cu" "F.Mask" "F.Paste")
			(net "ACT_HDD_20")
		)
		(pad "P12" smd rect
			(at -12.065 -1.82499 270)
			(size 0.6096 2.3622)
			(layers "F.Cu" "F.Mask" "F.Paste")
			(net "GND")
		)
		(pad "P13" smd rect
			(at -13.335 -1.82499 270)
			(size 0.6096 2.3622)
			(layers "F.Cu" "F.Mask" "F.Paste")
			(net "12V_PRE_20")
		)
		(pad "P14" smd rect
			(at -14.605 -1.82499 270)
			(size 0.6096 2.3622)
			(layers "F.Cu" "F.Mask" "F.Paste")
			(net "P12V_HDD20")
		)
		(pad "P15" smd rect
			(at -15.875 -1.82499 270)
			(size 0.6096 2.3622)
			(layers "F.Cu" "F.Mask" "F.Paste")
			(net "P12V_HDD20")
		)
		(pad "S1" smd rect
			(at 15.875 -1.82499 270)
			(size 0.6096 2.3622)
			(layers "F.Cu" "F.Mask" "F.Paste")
			(net "GND")
		)
		(pad "S2" smd rect
			(at 14.605 -1.82499 270)
			(size 0.6096 2.3622)
			(layers "F.Cu" "F.Mask" "F.Paste")
			(net "SAS_HDD_RX_P20")
		)
		(pad "S3" smd rect
			(at 13.335 -1.82499 270)
			(size 0.6096 2.3622)
			(layers "F.Cu" "F.Mask" "F.Paste")
			(net "SAS_HDD_RX_N20")
		)
		(pad "S4" smd rect
			(at 12.065 -1.82499 270)
			(size 0.6096 2.3622)
			(layers "F.Cu" "F.Mask" "F.Paste")
			(net "GND")
		)
		(pad "S5" smd rect
			(at 10.795 -1.82499 270)
			(size 0.6096 2.3622)
			(layers "F.Cu" "F.Mask" "F.Paste")
			(net "PHY_DRV_B_TO_SCC_B_20_DN")
		)
		(pad "S6" smd rect
			(at 9.525 -1.82499 270)
			(size 0.6096 2.3622)
			(layers "F.Cu" "F.Mask" "F.Paste")
			(net "PHY_DRV_B_TO_SCC_B_20_DP")
		)
		(pad "S7" smd rect
			(at 8.255 -1.82499 270)
			(size 0.6096 2.3622)
			(layers "F.Cu" "F.Mask" "F.Paste")
			(net "GND")
		)
		(pad "S8" smd rect
			(at 7.480046 2.845054 270)
			(size 0.508 2.3622)
			(layers "F.Cu" "F.Mask" "F.Paste")
			(net "GND")
		)
		(pad "S9" smd rect
			(at 6.679946 2.845054 270)
			(size 0.508 2.3622)
			(layers "F.Cu" "F.Mask" "F.Paste")
			(net "Net_444")
		)
		(pad "S10" smd rect
			(at 5.8801 2.845054 270)
			(size 0.508 2.3622)
			(layers "F.Cu" "F.Mask" "F.Paste")
			(net "Net_336")
		)
		(pad "S11" smd rect
			(at 5.08 2.845054 270)
			(size 0.508 2.3622)
			(layers "F.Cu" "F.Mask" "F.Paste")
			(net "GND")
		)
		(pad "S12" smd rect
			(at 4.2799 2.845054 270)
			(size 0.508 2.3622)
			(layers "F.Cu" "F.Mask" "F.Paste")
			(net "Net_372")
		)
		(pad "S13" smd rect
			(at 3.480054 2.845054 270)
			(size 0.508 2.3622)
			(layers "F.Cu" "F.Mask" "F.Paste")
			(net "Net_408")
		)
		(pad "S14" smd rect
			(at 2.679954 2.845054 270)
			(size 0.508 2.3622)
			(layers "F.Cu" "F.Mask" "F.Paste")
			(net "GND")
		)
		(zone
			(layer "F.Cu")
			(hatch none 0.5)
			(connect_pads
				(clearance 0)
			)
			(min_thickness 0.25)
			(keepout
				(tracks not_allowed)
				(vias allowed)
				(pads allowed)
				(copperpour not_allowed)
				(footprints allowed)
			)
			(placement
				(enabled no)
				(sheetname "")
			)
			(fill
				(thermal_gap 0.5)
				(thermal_bridge_width 0.5)
				(island_removal_mode 0)
			)
			(polygon
				(pts
					(xy 392.307572 -160.64865) (xy 385.233672 -160.64865) (xy 385.233672 -167.58285) (xy 386.338572 -167.58285)
					(xy 386.338572 -163.46805) (xy 390.961372 -163.46805) (xy 390.961372 -167.58285) (xy 392.307572 -167.58285)
				)
			)
		)
		(zone
			(layer "F.Cu")
			(hatch none 0.5)
			(connect_pads
				(clearance 0)
			)
			(min_thickness 0.25)
			(keepout
				(tracks allowed)
				(vias not_allowed)
				(pads allowed)
				(copperpour not_allowed)
				(footprints allowed)
			)
			(placement
				(enabled no)
				(sheetname "")
			)
			(fill
				(thermal_gap 0.5)
				(thermal_bridge_width 0.5)
				(island_removal_mode 0)
			)
			(polygon
				(pts
					(xy 392.307572 -160.64865) (xy 385.233672 -160.64865) (xy 385.233672 -167.58285) (xy 386.338572 -167.58285)
					(xy 386.338572 -163.46805) (xy 390.961372 -163.46805) (xy 390.961372 -167.58285) (xy 392.307572 -167.58285)
				)
			)
		)
		(zone
			(layer "F.Cu")
			(hatch none 0.5)
			(connect_pads
				(clearance 0)
			)
			(min_thickness 0.25)
			(keepout
				(tracks allowed)
				(vias not_allowed)
				(pads allowed)
				(copperpour not_allowed)
				(footprints allowed)
			)
			(placement
				(enabled no)
				(sheetname "")
			)
			(fill
				(thermal_gap 0.5)
				(thermal_bridge_width 0.5)
				(island_removal_mode 0)
			)
			(polygon
				(pts
					(xy 392.307572 -127.17145) (xy 385.233672 -127.17145) (xy 385.233672 -120.23725) (xy 386.338572 -120.23725)
					(xy 386.338572 -124.35205) (xy 390.961372 -124.35205) (xy 390.961372 -120.23725) (xy 392.307572 -120.23725)
				)
			)
		)
		(zone
			(layer "F.Cu")
			(hatch none 0.5)
			(connect_pads
				(clearance 0)
			)
			(min_thickness 0.25)
			(keepout
				(tracks not_allowed)
				(vias allowed)
				(pads allowed)
				(copperpour not_allowed)
				(footprints allowed)
			)
			(placement
				(enabled no)
				(sheetname "")
			)
			(fill
				(thermal_gap 0.5)
				(thermal_bridge_width 0.5)
				(island_removal_mode 0)
			)
			(polygon
				(pts
					(xy 392.307572 -127.17145) (xy 385.233672 -127.17145) (xy 385.233672 -120.23725) (xy 386.338572 -120.23725)
					(xy 386.338572 -124.35205) (xy 390.961372 -124.35205) (xy 390.961372 -120.23725) (xy 392.307572 -120.23725)
				)
			)
		)
		(zone
			(layers "F.Cu" "B.Cu" "In1.Cu" "In2.Cu" "In3.Cu" "In4.Cu" "In5.Cu" "In6.Cu")
			(hatch none 0.5)
			(connect_pads
				(clearance 0)
			)
			(min_thickness 0.25)
			(keepout
				(tracks not_allowed)
				(vias allowed)
				(pads allowed)
				(copperpour not_allowed)
				(footprints allowed)
			)
			(placement
				(enabled no)
				(sheetname "")
			)
			(fill
				(thermal_gap 0.5)
				(thermal_bridge_width 0.5)
				(island_removal_mode 0)
			)
			(polygon
				(pts
					(arc
						(start 389.424672 -125.035056)
						(mid 387.875272 -125.035056)
						(end 389.424672 -125.035056)
					)
				)
			)
		)
		(zone
			(layers "F.Cu" "B.Cu" "In1.Cu" "In2.Cu" "In3.Cu" "In4.Cu" "In5.Cu" "In6.Cu")
			(hatch none 0.5)
			(connect_pads
				(clearance 0)
			)
			(min_thickness 0.25)
			(keepout
				(tracks not_allowed)
				(vias allowed)
				(pads allowed)
				(copperpour not_allowed)
				(footprints allowed)
			)
			(placement
				(enabled no)
				(sheetname "")
			)
			(fill
				(thermal_gap 0.5)
				(thermal_bridge_width 0.5)
				(island_removal_mode 0)
			)
			(polygon
				(pts
					(arc
						(start 389.627872 -162.785044)
						(mid 387.672072 -162.785044)
						(end 389.627872 -162.785044)
					)
				)
			)
		)
	)
	(footprint ""
		(layer "F.Cu")
		(at 20.7518 -229.50932 180)
		(property "Reference" "R1114"
			(at 0 0 180)
			(layer "F.SilkS")
			(hide yes)
			(effects
				(font
					(size 1.27 1.27)
				)
			)
		)
		(property "Value" "0R2J-2-GP"
			(at 0.064008 -3.993896 180)
			(unlocked yes)
			(layer "F.Fab")
			(hide yes)
			(effects
				(font
					(size 1.016 1.016)
					(thickness 0.1524)
				)
			)
		)
		(property "Device Type" "R402H16"
			(at 0.064008 -5.517896 180)
			(unlocked yes)
			(layer "F.Fab")
			(hide yes)
			(effects
				(font
					(size 1.016 1.016)
					(thickness 0.1524)
				)
			)
		)
		(duplicate_pad_numbers_are_jumpers no)
		(fp_line
			(start 0.508 -0.9398)
			(end -0.508 -0.9398)
			(stroke
				(width 0.1524)
				(type default)
			)
			(layer "F.SilkS")
		)
		(fp_line
			(start -0.508 -0.9398)
			(end -0.508 0.9398)
			(stroke
				(width 0.1524)
				(type default)
			)
			(layer "F.SilkS")
		)
		(fp_rect
			(start -0.508 0.9398)
			(end 0.508 -0.9398)
			(stroke
				(width 0)
				(type default)
			)
			(fill no)
			(layer "F.CrtYd")
		)
		(fp_rect
			(start -0.508 0.9398)
			(end 0.508 -0.9398)
			(stroke
				(width 0)
				(type default)
			)
			(fill no)
			(layer "F.Fab")
		)
		(pad "1" smd custom
			(at 0 -0.4445 180)
			(size 0.1397 0.1397)
			(layers "F.Cu" "F.Mask" "F.Paste")
			(net "P5V_B_1_ROVP")
			(options
				(clearance outline)
				(anchor circle)
			)
			(primitives
				(gr_poly
					(pts
						(arc
							(start -0.1778 -0.2794)
							(mid -0.249642 -0.249642)
							(end -0.2794 -0.1778)
						)
						(arc
							(start -0.2794 0.1778)
							(mid -0.249642 0.249642)
							(end -0.1778 0.2794)
						)
						(arc
							(start 0.1778 0.2794)
							(mid 0.249642 0.249642)
							(end 0.2794 0.1778)
						)
						(arc
							(start 0.2794 -0.1778)
							(mid 0.249642 -0.249642)
							(end 0.1778 -0.2794)
						)
					)
					(width 0)
					(fill yes)
				)
			)
		)
		(pad "2" smd custom
			(at 0 0.4445 180)
			(size 0.1397 0.1397)
			(layers "F.Cu" "F.Mask" "F.Paste")
			(net "AGND_P5V_B_1")
			(options
				(clearance outline)
				(anchor circle)
			)
			(primitives
				(gr_poly
					(pts
						(arc
							(start -0.1778 -0.2794)
							(mid -0.249642 -0.249642)
							(end -0.2794 -0.1778)
						)
						(arc
							(start -0.2794 0.1778)
							(mid -0.249642 0.249642)
							(end -0.1778 0.2794)
						)
						(arc
							(start 0.1778 0.2794)
							(mid 0.249642 0.249642)
							(end 0.2794 0.1778)
						)
						(arc
							(start 0.2794 -0.1778)
							(mid 0.249642 -0.249642)
							(end 0.1778 -0.2794)
						)
					)
					(width 0)
					(fill yes)
				)
			)
		)
	)
	(footprint ""
		(layer "F.Cu")
		(at 314.623196 -374.1928 90)
		(property "Reference" "R975"
			(at 0 0 90)
			(layer "F.SilkS")
			(hide yes)
			(effects
				(font
					(size 1.27 1.27)
				)
			)
		)
		(property "Value" "270R5J-2-GP"
			(at 0 -8.9535 90)
			(unlocked yes)
			(layer "F.Fab")
			(hide yes)
			(effects
				(font
					(size 1.27 1.016)
					(thickness 0.1524)
				)
			)
		)
		(property "Device Type" "R805H24"
			(at 0 -10.6299 90)
			(unlocked yes)
			(layer "F.Fab")
			(hide yes)
			(effects
				(font
					(size 1.27 1.016)
					(thickness 0.1524)
				)
			)
		)
		(duplicate_pad_numbers_are_jumpers no)
		(fp_line
			(start 0.889 -1.7018)
			(end -0.889 -1.7018)
			(stroke
				(width 0.1524)
				(type default)
			)
			(layer "F.SilkS")
		)
		(fp_line
			(start 0.889 -1.7018)
			(end 0.889 -0.381)
			(stroke
				(width 0.1524)
				(type default)
			)
			(layer "F.SilkS")
		)
		(fp_line
			(start -0.889 -1.7018)
			(end -0.889 0.2794)
			(stroke
				(width 0.1524)
				(type default)
			)
			(layer "F.SilkS")
		)
		(fp_line
			(start -0.889 0.0762)
			(end -0.889 1.7018)
			(stroke
				(width 0.1524)
				(type default)
			)
			(layer "F.SilkS")
		)
		(fp_line
			(start 0.889 1.7018)
			(end 0.889 -0.508)
			(stroke
				(width 0.1524)
				(type default)
			)
			(layer "F.SilkS")
		)
		(fp_line
			(start -0.889 1.7018)
			(end 0.889 1.7018)
			(stroke
				(width 0.1524)
				(type default)
			)
			(layer "F.SilkS")
		)
		(fp_poly
			(pts
				(xy 0.9652 -1.778) (xy 0.9652 1.778) (xy -0.9652 1.778) (xy -0.9652 -1.778)
			)
			(stroke
				(width 0)
				(type default)
			)
			(fill no)
			(layer "F.CrtYd")
		)
		(fp_rect
			(start -0.9652 1.778)
			(end 0.9652 -1.778)
			(stroke
				(width 0)
				(type default)
			)
			(fill no)
			(layer "F.Fab")
		)
		(pad "1" smd rect
			(at 0 -0.9652 90)
			(size 1.397 1.143)
			(layers "F.Cu" "F.Mask" "F.Paste")
			(net "FAN_LED_BLUE2")
		)
		(pad "2" smd rect
			(at 0 0.9652 90)
			(size 1.397 1.143)
			(layers "F.Cu" "F.Mask" "F.Paste")
			(net "FAN_BLUE2")
		)
	)
)
